# T6G (Grand Teton) — schematic netlist excerpt (pin names and nets, part order shuffled) for the footprints in the layout excerpt that follows; sources: Cadence DE-HDL packaged netlist, KiCad conversion of 04192023_DAF0TMB3IC0_F0TG_MB_C_brd_V02_OCP.brd

J18  SCONN288_DDR506112002KQ  IO  pkg DDR288S_1-1VXC  page 94
  VIN_BULK0  = P12V_MEM_CPU0
  RFU0  = NC
  VIN_MGMT  = P3V3_AUX
  HSCL  = I3C_SPD_DDRI_CPU0_SCL
  HSDA  = I3C_SPD_DDRI_CPU0_SDA
  VSS0  = GND
  DQ0_A  = M_I_CPU0_SA_DQ<0>
  VSS1  = GND
  DQ1_A  = M_I_CPU0_SA_DQ<1>
  VSS2  = GND
  DQS0_A_T  = M_I_CPU0_SA_DQS_DP<0>
  DQS0_A_C  = M_I_CPU0_SA_DQS_DN<0>
  VSS3  = GND
  DQ4_A  = M_I_CPU0_SA_DQ<4>
  VSS4  = GND
  DQ5_A  = M_I_CPU0_SA_DQ<5>
  VSS5  = GND
  DQ8_A  = M_I_CPU0_SA_DQ<8>
  VSS6  = GND
  DQ9_A  = M_I_CPU0_SA_DQ<9>
  VSS7  = GND
  DQS1_A_T  = M_I_CPU0_SA_DQS_DP<1>
  DQS1_A_C  = M_I_CPU0_SA_DQS_DN<1>
  VSS8  = GND
  DQ12_A  = M_I_CPU0_SA_DQ<12>
  VSS9  = GND
  DQ13_A  = M_I_CPU0_SA_DQ<13>
  VSS10  = GND
  DQ16_A  = M_I_CPU0_SA_DQ<16>
  VSS11  = GND
  DQ17_A  = M_I_CPU0_SA_DQ<17>
  VSS12  = GND
  DQS2_A_T  = M_I_CPU0_SA_DQS_DP<2>
  DQS2_A_C  = M_I_CPU0_SA_DQS_DN<2>
  VSS13  = GND
  DQ20_A  = M_I_CPU0_SA_DQ<20>
  VSS14  = GND
  DQ21_A  = M_I_CPU0_SA_DQ<21>
  VSS15  = GND
  DQ24_A  = M_I_CPU0_SA_DQ<24>
  VSS16  = GND
  DQ25_A  = M_I_CPU0_SA_DQ<25>
  VSS17  = GND
  DQS3_A_T  = M_I_CPU0_SA_DQS_DP<3>
  DQS3_A_C  = M_I_CPU0_SA_DQS_DN<3>
  VSS18  = GND
  DQ28_A  = M_I_CPU0_SA_DQ<28>
  VSS19  = GND
  DQ29_A  = M_I_CPU0_SA_DQ<29>
  VSS20  = GND
  CB0_A  = M_I_CPU0_SA_CB<0>
  VSS21  = GND
  CB1_A  = M_I_CPU0_SA_CB<1>
  VSS22  = GND
  DQS4_A_T  = M_I_CPU0_SA_DQS_DP<4>
  DQS4_A_C  = M_I_CPU0_SA_DQS_DN<4>
  VSS23  = GND
  CB4_A  = M_I_CPU0_SA_CB<4>
  VSS24  = GND
  CB5_A  = M_I_CPU0_SA_CB<5>
  VSS25  = GND
  ALERT_N  = M_I_CPU0_ALERT_N
  VSS26  = GND
  CS0_A_N  = M_I_CPU0_SA_CS_N<0>
  VSS27  = GND
  CA0_A  = M_I_CPU0_SA_CA<0>
  VSS28  = GND
  CA2_A  = M_I_CPU0_SA_CA<2>
  VSS29  = GND
  CA4_A  = M_I_CPU0_SA_CA<4>
  VSS30  = GND
  CA6_A  = M_I_CPU0_SA_CA<6>
  VSS31  = GND
  PAR_A  = M_I_CPU0_SA_PAR
  VSS32  = GND
  CA0_B  = M_I_CPU0_SB_CA<0>
  VSS33  = GND
  CA2_B  = M_I_CPU0_SB_CA<2>
  VSS34  = GND
  CA4_B  = M_I_CPU0_SB_CA<4>
  VSS35  = GND
  CA6_B  = M_I_CPU0_SB_CA<6>
  VSS36  = GND
  CS0_B_N  = M_I_CPU0_SB_CS_N<0>
  VSS37  = GND
  \lbd||rsp_a_n\  = M_I_CPU0_SA_RSP<0>
  \lbs||rsp_b_n\  = M_I_CPU0_SB_RSP<0>
  VSS38  = GND
  CB4_B  = M_I_CPU0_SB_CB<4>
  VSS39  = GND
  CB5_B  = M_I_CPU0_SB_CB<5>
  VSS40  = GND
  \dqs9_b_t||tdqs9_b_t||dbi4_b_n\  = M_I_CPU0_SB_DQS_DP<9>
  \dqs9_b_c||tdqs9_b_c\  = M_I_CPU0_SB_DQS_DN<9>
  VSS41  = GND
  CB0_B  = M_I_CPU0_SB_CB<0>
  VSS42  = GND
  CB1_B  = M_I_CPU0_SB_CB<1>
  VSS43  = GND
  DQ0_B  = M_I_CPU0_SB_DQ<0>
  VSS44  = GND
  DQ1_B  = M_I_CPU0_SB_DQ<1>
  VSS45  = GND
  DQS0_B_T  = M_I_CPU0_SB_DQS_DP<0>
  DQS0_B_C  = M_I_CPU0_SB_DQS_DN<0>
  VSS46  = GND
  DQ4_B  = M_I_CPU0_SB_DQ<4>
  VSS47  = GND
  DQ5_B  = M_I_CPU0_SB_DQ<5>
  VSS48  = GND
  DQ8_B  = M_I_CPU0_SB_DQ<8>
  VSS49  = GND
  DQ9_B  = M_I_CPU0_SB_DQ<9>
  VSS50  = GND
  DQS1_B_T  = M_I_CPU0_SB_DQS_DP<1>
  DQS1_B_C  = M_I_CPU0_SB_DQS_DN<1>
  VSS51  = GND
  DQ12_B  = M_I_CPU0_SB_DQ<12>
  VSS52  = GND
  DQ13_B  = M_I_CPU0_SB_DQ<13>
  VSS53  = GND
  DQ16_B  = M_I_CPU0_SB_DQ<16>
  VSS54  = GND
  DQ17_B  = M_I_CPU0_SB_DQ<17>
  VSS55  = GND
  DQS2_B_T  = M_I_CPU0_SB_DQS_DP<2>
  DQS2_B_C  = M_I_CPU0_SB_DQS_DN<2>
  VSS56  = GND
  DQ20_B  = M_I_CPU0_SB_DQ<20>
  VSS57  = GND
  DQ21_B  = M_I_CPU0_SB_DQ<21>
  VSS58  = GND
  DQ24_B  = M_I_CPU0_SB_DQ<24>
  VSS59  = GND
  DQ25_B  = M_I_CPU0_SB_DQ<25>
  VSS60  = GND
  DQS3_B_T  = M_I_CPU0_SB_DQS_DP<3>
  DQS3_B_C  = M_I_CPU0_SB_DQS_DN<3>
  VSS61  = GND
  DQ28_B  = M_I_CPU0_SB_DQ<28>
  VSS62  = GND
  DQ29_B  = M_I_CPU0_SB_DQ<29>
  VSS63  = GND
  RFU1  = NC
  VIN_BULK1  = P12V_MEM_CPU0
  VIN_BULK2  = P12V_MEM_CPU0
  \pwr_good||fail_n\  = PWRGD_CHI_CPU0_DIMM
  HAS  = PD_CHI_CPU0_DIMM_SAA
  RFU2  = NC
  RFU3  = NC
  VSS64  = GND
  DQ2_A  = M_I_CPU0_SA_DQ<2>
  VSS65  = GND
  DQ3_A  = M_I_CPU0_SA_DQ<3>
  VSS66  = GND
  \dqs5_a_c||tdqs5_a_c||dqs5_a_t||tdqs5_a_t\  = M_I_CPU0_SA_DQS_DN<5>
  \dqs5_a_t||tdqs5_a_t\  = M_I_CPU0_SA_DQS_DP<5>
  VSS67  = GND
  DQ6_A  = M_I_CPU0_SA_DQ<6>
  VSS68  = GND
  DQ7_A  = M_I_CPU0_SA_DQ<7>
  VSS69  = GND
  DQ10_A  = M_I_CPU0_SA_DQ<10>
  VSS70  = GND
  DQ11_A  = M_I_CPU0_SA_DQ<11>
  VSS71  = GND
  \dqs6_a_c||tdqs6_a_c||dqs6_a_t||tdqs6_a_t\  = M_I_CPU0_SA_DQS_DN<6>
  \dqs6_a_t||tdqs6_a_t\  = M_I_CPU0_SA_DQS_DP<6>
  VSS72  = GND
  DQ14_A  = M_I_CPU0_SA_DQ<14>
  VSS73  = GND
  DQ15_A  = M_I_CPU0_SA_DQ<15>
  VSS74  = GND
  DQ18_A  = M_I_CPU0_SA_DQ<18>
  VSS75  = GND
  DQ19_A  = M_I_CPU0_SA_DQ<19>
  VSS76  = GND
  \dqs7_a_c||tdqs7_a_c\  = M_I_CPU0_SA_DQS_DN<7>
  \dqs7_a_t||tdqs7_a_t\  = M_I_CPU0_SA_DQS_DP<7>
  VSS77  = GND
  DQ22_A  = M_I_CPU0_SA_DQ<22>
  VSS78  = GND
  DQ23_A  = M_I_CPU0_SA_DQ<23>
  VSS79  = GND
  DQ26_A  = M_I_CPU0_SA_DQ<26>
  VSS80  = GND
  DQ27_A  = M_I_CPU0_SA_DQ<27>
  VSS81  = GND
  \dqs8_a_c||tdqs8_a_c\  = M_I_CPU0_SA_DQS_DN<8>
  \dqs8_a_t||tdqs8_a_t\  = M_I_CPU0_SA_DQS_DP<8>
  VSS82  = GND
  DQ30_A  = M_I_CPU0_SA_DQ<30>
  VSS83  = GND
  DQ31_A  = M_I_CPU0_SA_DQ<31>
  VSS84  = GND
  CB2_A  = M_I_CPU0_SA_CB<2>
  VSS85  = GND
  CB3_A  = M_I_CPU0_SA_CB<3>
  VSS86  = GND
  \dqs9_a_c||tdqs9_a_c\  = M_I_CPU0_SA_DQS_DN<9>
  \dqs9_a_t||tdqs9_a_t\  = M_I_CPU0_SA_DQS_DP<9>
  VSS87  = GND
  CB6_A  = M_I_CPU0_SA_CB<6>
  VSS88  = GND
  CB7_A  = M_I_CPU0_SA_CB<7>
  VSS89  = GND
  RESET_N  = M_I_CPU0_RESET_N
  VSS90  = GND
  CS1_A_N  = M_I_CPU0_SA_CS_N<1>
  VSS91  = GND
  CA1_A  = M_I_CPU0_SA_CA<1>
  VSS92  = GND
  CA3_A  = M_I_CPU0_SA_CA<3>
  VSS93  = GND
  CA5_A  = M_I_CPU0_SA_CA<5>
  VSS94  = GND
  CK_T  = M_I_CPU0_CLK_DP<0>
  CK_C  = M_I_CPU0_CLK_DN<0>
  VSS95  = GND
  RFU4  = NC
  CA1_B  = M_I_CPU0_SB_CA<1>
  VSS96  = GND
  CA3_B  = M_I_CPU0_SB_CA<3>
  VSS97  = GND
  CA5_B  = M_I_CPU0_SB_CA<5>
  VSS98  = GND
  PAR_B  = M_I_CPU0_SB_PAR
  VSS99  = GND
  CS1_B_N  = M_I_CPU0_SB_CS_N<1>
  VSS100  = GND
  RFU5  = NC
  RFU6  = NC
  VSS101  = GND
  CB6_B  = M_I_CPU0_SB_CB<6>
  VSS102  = GND
  CB7_B  = M_I_CPU0_SB_CB<7>
  VSS103  = GND
  DQS4_B_C  = M_I_CPU0_SB_DQS_DN<4>
  DQS4_B_T  = M_I_CPU0_SB_DQS_DP<4>
  VSS104  = GND
  CB2_B  = M_I_CPU0_SB_CB<2>
  VSS105  = GND
  CB3_B  = M_I_CPU0_SB_CB<3>
  VSS106  = GND
  DQ2_B  = M_I_CPU0_SB_DQ<2>
  VSS107  = GND
  DQ3_B  = M_I_CPU0_SB_DQ<3>
  VSS108  = GND
  \dqs5_b_c||tdqs5_b_c\  = M_I_CPU0_SB_DQS_DN<5>
  \dqs5_b_t||tdqs5_b_t\  = M_I_CPU0_SB_DQS_DP<5>
  VSS109  = GND
  DQ6_B  = M_I_CPU0_SB_DQ<6>
  VSS110  = GND
  DQ7_B  = M_I_CPU0_SB_DQ<7>
  VSS111  = GND
  DQ10_B  = M_I_CPU0_SB_DQ<10>
  VSS112  = GND
  DQ11_B  = M_I_CPU0_SB_DQ<11>
  VSS113  = GND
  \dqs6_b_c||tdqs6_b_c\  = M_I_CPU0_SB_DQS_DN<6>
  \dqs6_b_t||tdqs6_b_t\  = M_I_CPU0_SB_DQS_DP<6>
  VSS114  = GND
  DQ14_B  = M_I_CPU0_SB_DQ<14>
  VSS115  = GND
  DQ15_B  = M_I_CPU0_SB_DQ<15>
  VSS116  = GND
  DQ18_B  = M_I_CPU0_SB_DQ<18>
  VSS117  = GND
  DQ19_B  = M_I_CPU0_SB_DQ<19>
  VSS118  = GND
  \dqs7_b_c||tdqs7_b_c\  = M_I_CPU0_SB_DQS_DN<7>
  \dqs7_b_t||tdqs7_b_t\  = M_I_CPU0_SB_DQS_DP<7>
  VSS119  = GND
  DQ22_B  = M_I_CPU0_SB_DQ<22>
  VSS120  = GND
  DQ23_B  = M_I_CPU0_SB_DQ<23>
  VSS121  = GND
  DQ26_B  = M_I_CPU0_SB_DQ<26>
  VSS122  = GND
  DQ27_B  = M_I_CPU0_SB_DQ<27>
  VSS123  = GND
  \dqs8_b_c||tdqs8_b_c\  = M_I_CPU0_SB_DQS_DN<8>
  \dqs8_b_t||tdqs8_b_t\  = M_I_CPU0_SB_DQS_DP<8>
  VSS124  = GND
  DQ30_B  = M_I_CPU0_SB_DQ<30>
  VSS125  = GND
  DQ31_B  = M_I_CPU0_SB_DQ<31>
  VSS126  = GND
  G1  = GND
  G2  = GND
  G3  = GND

(kicad_pcb
	(version 20260206)
	(generator "pcbnew")
	(generator_version "10.0")
	(general
		(thickness 1.6)
		(legacy_teardrops no)
	)
	(paper "A4")
	(title_block
		(title "04192023_DAF0TMB3IC0_F0TG_MB_C_brd_V02_OCP.brd")
		(comment 1 "Grand Teton / footprint 4761 of 8354 (J18), pads 139-184 of 291")
	)
	(layers
		(0 "F.Cu" signal "TOP")
		(4 "In1.Cu" signal "GND")
		(6 "In2.Cu" signal "IN1")
		(8 "In3.Cu" signal "GND1")
		(10 "In4.Cu" signal "IN2")
		(12 "In5.Cu" signal "GND2")
		(14 "In6.Cu" signal "IN3")
		(16 "In7.Cu" signal "GND3")
		(18 "In8.Cu" signal "VCC")
		(20 "In9.Cu" signal "VCC1")
		(22 "In10.Cu" signal "GND4")
		(24 "In11.Cu" signal "IN4")
		(26 "In12.Cu" signal "GND5")
		(28 "In13.Cu" signal "IN5")
		(30 "In14.Cu" signal "GND6")
		(32 "In15.Cu" signal "IN6")
		(34 "In16.Cu" signal "GND7")
		(2 "B.Cu" signal "BOTTOM")
		(9 "F.Adhes" user "F.Adhesive")
		(11 "B.Adhes" user "B.Adhesive")
		(13 "F.Paste" user "Package Geometry/Pastemask Top")
		(15 "B.Paste" user "Package Geometry/Pastemask Bottom")
		(5 "F.SilkS" user "Ref Des/Silkscreen Top")
		(7 "B.SilkS" user "Ref Des/Silkscreen Bottom")
		(1 "F.Mask" user "Board Geometry/Soldermask Top")
		(3 "B.Mask" user "Board Geometry/Soldermask Bottom")
		(17 "Dwgs.User" user "User.Drawings")
		(19 "Cmts.User" user "User.Comments")
		(21 "Eco1.User" user "User.Eco1")
		(23 "Eco2.User" user "User.Eco2")
		(25 "Edge.Cuts" user "Board Geometry/Outline")
		(27 "Margin" user)
		(31 "F.CrtYd" user "Package Geometry/Place Bound Top")
		(29 "B.CrtYd" user "Package Geometry/Place Bound Bottom")
		(35 "F.Fab" user "Ref Des/Assembly Top")
		(33 "B.Fab" user "Ref Des/Assembly Bottom")
	)
	(footprint ""
		(layer "F.Cu")
		(at 429.506126 -255.560068 180)
		(property "Reference" "J18"
			(at 0.484632 -81.752948 0)
			(unlocked yes)
			(layer "F.SilkS")
			(effects
				(font
					(size 0.7874 0.5842)
					(thickness 0.1524)
				)
			)
		)
		(property "Value" ""
			(at 0 0 180)
			(layer "F.Fab")
			(effects
				(font
					(size 1.27 1.27)
				)
			)
		)
		(duplicate_pad_numbers_are_jumpers no)
		(pad "139" smd rect
			(at -2.050034 59.075066 90)
			(size 0.519938 1.4986)
			(layers "F.Cu" "F.Mask" "F.Paste")
			(net "GND")
		)
		(pad "140" smd rect
			(at -2.050034 59.92495 90)
			(size 0.519938 1.4986)
			(layers "F.Cu" "F.Mask" "F.Paste")
			(net "M_I_CPU0_SB_DQ<28>")
		)
		(pad "141" smd rect
			(at -2.050034 60.775088 90)
			(size 0.519938 1.4986)
			(layers "F.Cu" "F.Mask" "F.Paste")
			(net "GND")
		)
		(pad "142" smd rect
			(at -2.050034 61.624972 90)
			(size 0.519938 1.4986)
			(layers "F.Cu" "F.Mask" "F.Paste")
			(net "M_I_CPU0_SB_DQ<29>")
		)
		(pad "143" smd rect
			(at -2.050034 62.47511 90)
			(size 0.519938 1.4986)
			(layers "F.Cu" "F.Mask" "F.Paste")
			(net "GND")
		)
		(pad "144" smd rect
			(at -2.050034 63.324994 90)
			(size 0.519938 1.4986)
			(layers "F.Cu" "F.Mask" "F.Paste")
			(net "Net_2362")
		)
		(pad "145" smd rect
			(at 2.050034 -63.324994 90)
			(size 0.519938 1.4986)
			(layers "F.Cu" "F.Mask" "F.Paste")
			(net "P12V_MEM_CPU0")
		)
		(pad "146" smd rect
			(at 2.050034 -62.47511 90)
			(size 0.519938 1.4986)
			(layers "F.Cu" "F.Mask" "F.Paste")
			(net "P12V_MEM_CPU0")
		)
		(pad "147" smd rect
			(at 2.050034 -61.624972 90)
			(size 0.519938 1.4986)
			(layers "F.Cu" "F.Mask" "F.Paste")
			(net "PWRGD_CHI_CPU0_DIMM")
		)
		(pad "148" smd rect
			(at 2.050034 -60.775088 90)
			(size 0.519938 1.4986)
			(layers "F.Cu" "F.Mask" "F.Paste")
			(net "PD_CHI_CPU0_DIMM_SAA")
		)
		(pad "149" smd rect
			(at 2.050034 -59.92495 90)
			(size 0.519938 1.4986)
			(layers "F.Cu" "F.Mask" "F.Paste")
			(net "Net_2363")
		)
		(pad "150" smd rect
			(at 2.050034 -59.075066 90)
			(size 0.519938 1.4986)
			(layers "F.Cu" "F.Mask" "F.Paste")
			(net "Net_2364")
		)
		(pad "151" smd rect
			(at 2.050034 -58.224928 90)
			(size 0.519938 1.4986)
			(layers "F.Cu" "F.Mask" "F.Paste")
			(net "GND")
		)
		(pad "152" smd rect
			(at 2.050034 -57.375044 90)
			(size 0.519938 1.4986)
			(layers "F.Cu" "F.Mask" "F.Paste")
			(net "M_I_CPU0_SA_DQ<2>")
		)
		(pad "153" smd rect
			(at 2.050034 -56.524906 90)
			(size 0.519938 1.4986)
			(layers "F.Cu" "F.Mask" "F.Paste")
			(net "GND")
		)
		(pad "154" smd rect
			(at 2.050034 -55.675022 90)
			(size 0.519938 1.4986)
			(layers "F.Cu" "F.Mask" "F.Paste")
			(net "M_I_CPU0_SA_DQ<3>")
		)
		(pad "155" smd rect
			(at 2.050034 -54.824884 90)
			(size 0.519938 1.4986)
			(layers "F.Cu" "F.Mask" "F.Paste")
			(net "GND")
		)
		(pad "156" smd rect
			(at 2.050034 -53.975 90)
			(size 0.519938 1.4986)
			(layers "F.Cu" "F.Mask" "F.Paste")
			(net "M_I_CPU0_SA_DQS_DN<5>")
		)
		(pad "157" smd rect
			(at 2.050034 -53.125116 90)
			(size 0.519938 1.4986)
			(layers "F.Cu" "F.Mask" "F.Paste")
			(net "M_I_CPU0_SA_DQS_DP<5>")
		)
		(pad "158" smd rect
			(at 2.050034 -52.274978 90)
			(size 0.519938 1.4986)
			(layers "F.Cu" "F.Mask" "F.Paste")
			(net "GND")
		)
		(pad "159" smd rect
			(at 2.050034 -51.425094 90)
			(size 0.519938 1.4986)
			(layers "F.Cu" "F.Mask" "F.Paste")
			(net "M_I_CPU0_SA_DQ<6>")
		)
		(pad "160" smd rect
			(at 2.050034 -50.574956 90)
			(size 0.519938 1.4986)
			(layers "F.Cu" "F.Mask" "F.Paste")
			(net "GND")
		)
		(pad "161" smd rect
			(at 2.050034 -49.725072 90)
			(size 0.519938 1.4986)
			(layers "F.Cu" "F.Mask" "F.Paste")
			(net "M_I_CPU0_SA_DQ<7>")
		)
		(pad "162" smd rect
			(at 2.050034 -48.874934 90)
			(size 0.519938 1.4986)
			(layers "F.Cu" "F.Mask" "F.Paste")
			(net "GND")
		)
		(pad "163" smd rect
			(at 2.050034 -48.02505 90)
			(size 0.519938 1.4986)
			(layers "F.Cu" "F.Mask" "F.Paste")
			(net "M_I_CPU0_SA_DQ<10>")
		)
		(pad "164" smd rect
			(at 2.050034 -47.174912 90)
			(size 0.519938 1.4986)
			(layers "F.Cu" "F.Mask" "F.Paste")
			(net "GND")
		)
		(pad "165" smd rect
			(at 2.050034 -46.325028 90)
			(size 0.519938 1.4986)
			(layers "F.Cu" "F.Mask" "F.Paste")
			(net "M_I_CPU0_SA_DQ<11>")
		)
		(pad "166" smd rect
			(at 2.050034 -45.47489 90)
			(size 0.519938 1.4986)
			(layers "F.Cu" "F.Mask" "F.Paste")
			(net "GND")
		)
		(pad "167" smd rect
			(at 2.050034 -44.625006 90)
			(size 0.519938 1.4986)
			(layers "F.Cu" "F.Mask" "F.Paste")
			(net "M_I_CPU0_SA_DQS_DN<6>")
		)
		(pad "168" smd rect
			(at 2.050034 -43.775122 90)
			(size 0.519938 1.4986)
			(layers "F.Cu" "F.Mask" "F.Paste")
			(net "M_I_CPU0_SA_DQS_DP<6>")
		)
		(pad "169" smd rect
			(at 2.050034 -42.924984 90)
			(size 0.519938 1.4986)
			(layers "F.Cu" "F.Mask" "F.Paste")
			(net "GND")
		)
		(pad "170" smd rect
			(at 2.050034 -42.0751 90)
			(size 0.519938 1.4986)
			(layers "F.Cu" "F.Mask" "F.Paste")
			(net "M_I_CPU0_SA_DQ<14>")
		)
		(pad "171" smd rect
			(at 2.050034 -41.224962 90)
			(size 0.519938 1.4986)
			(layers "F.Cu" "F.Mask" "F.Paste")
			(net "GND")
		)
		(pad "172" smd rect
			(at 2.050034 -40.375078 90)
			(size 0.519938 1.4986)
			(layers "F.Cu" "F.Mask" "F.Paste")
			(net "M_I_CPU0_SA_DQ<15>")
		)
		(pad "173" smd rect
			(at 2.050034 -39.52494 90)
			(size 0.519938 1.4986)
			(layers "F.Cu" "F.Mask" "F.Paste")
			(net "GND")
		)
		(pad "174" smd rect
			(at 2.050034 -38.675056 90)
			(size 0.519938 1.4986)
			(layers "F.Cu" "F.Mask" "F.Paste")
			(net "M_I_CPU0_SA_DQ<18>")
		)
		(pad "175" smd rect
			(at 2.050034 -37.824918 90)
			(size 0.519938 1.4986)
			(layers "F.Cu" "F.Mask" "F.Paste")
			(net "GND")
		)
		(pad "176" smd rect
			(at 2.050034 -36.975034 90)
			(size 0.519938 1.4986)
			(layers "F.Cu" "F.Mask" "F.Paste")
			(net "M_I_CPU0_SA_DQ<19>")
		)
		(pad "177" smd rect
			(at 2.050034 -36.124896 90)
			(size 0.519938 1.4986)
			(layers "F.Cu" "F.Mask" "F.Paste")
			(net "GND")
		)
		(pad "178" smd rect
			(at 2.050034 -35.275012 90)
			(size 0.519938 1.4986)
			(layers "F.Cu" "F.Mask" "F.Paste")
			(net "M_I_CPU0_SA_DQS_DN<7>")
		)
		(pad "179" smd rect
			(at 2.050034 -34.425128 90)
			(size 0.519938 1.4986)
			(layers "F.Cu" "F.Mask" "F.Paste")
			(net "M_I_CPU0_SA_DQS_DP<7>")
		)
		(pad "180" smd rect
			(at 2.050034 -33.57499 90)
			(size 0.519938 1.4986)
			(layers "F.Cu" "F.Mask" "F.Paste")
			(net "GND")
		)
		(pad "181" smd rect
			(at 2.050034 -32.725106 90)
			(size 0.519938 1.4986)
			(layers "F.Cu" "F.Mask" "F.Paste")
			(net "M_I_CPU0_SA_DQ<22>")
		)
		(pad "182" smd rect
			(at 2.050034 -31.874968 90)
			(size 0.519938 1.4986)
			(layers "F.Cu" "F.Mask" "F.Paste")
			(net "GND")
		)
		(pad "183" smd rect
			(at 2.050034 -31.025084 90)
			(size 0.519938 1.4986)
			(layers "F.Cu" "F.Mask" "F.Paste")
			(net "M_I_CPU0_SA_DQ<23>")
		)
		(pad "184" smd rect
			(at 2.050034 -30.174946 90)
			(size 0.519938 1.4986)
			(layers "F.Cu" "F.Mask" "F.Paste")
			(net "GND")
		)
	)
)
